# T6G (Grand Teton) — schematic netlist excerpt (pin names and nets, part order shuffled) for the footprints in the layout excerpt that follows; sources: Cadence DE-HDL packaged netlist, KiCad conversion of 04192023_DAF0TMB3IC0_F0TG_MB_C_brd_V02_OCP.brd

C653  Q_CAP  1UF 4V 20% X6S  pkg 0201  page 290 : A = P0V9_CPU0_RT1_2A ; B = GND
PC276  Q_CAPP  220UF 4V 20% SPCAP  pkg SMLF  page 211 : A = PVDDCR_CPU0_P1 ; B = GND
PR324  Q_RES  0 5% CHIP  pkg 0402LF  page 194 : A = PVDDCR_CPU0_P0_VOS1 ; B = PVDDCR_CPU0_P0

(kicad_pcb
	(version 20260206)
	(generator "pcbnew")
	(generator_version "10.0")
	(general
		(thickness 1.6)
		(legacy_teardrops no)
	)
	(paper "A4")
	(title_block
		(title "04192023_DAF0TMB3IC0_F0TG_MB_C_brd_V02_OCP.brd")
		(comment 1 "Grand Teton / footprints 5110-5112 of 8354")
	)
	(layers
		(0 "F.Cu" signal "TOP")
		(4 "In1.Cu" signal "GND")
		(6 "In2.Cu" signal "IN1")
		(8 "In3.Cu" signal "GND1")
		(10 "In4.Cu" signal "IN2")
		(12 "In5.Cu" signal "GND2")
		(14 "In6.Cu" signal "IN3")
		(16 "In7.Cu" signal "GND3")
		(18 "In8.Cu" signal "VCC")
		(20 "In9.Cu" signal "VCC1")
		(22 "In10.Cu" signal "GND4")
		(24 "In11.Cu" signal "IN4")
		(26 "In12.Cu" signal "GND5")
		(28 "In13.Cu" signal "IN5")
		(30 "In14.Cu" signal "GND6")
		(32 "In15.Cu" signal "IN6")
		(34 "In16.Cu" signal "GND7")
		(2 "B.Cu" signal "BOTTOM")
		(9 "F.Adhes" user "F.Adhesive")
		(11 "B.Adhes" user "B.Adhesive")
		(13 "F.Paste" user "Package Geometry/Pastemask Top")
		(15 "B.Paste" user "Package Geometry/Pastemask Bottom")
		(5 "F.SilkS" user "Ref Des/Silkscreen Top")
		(7 "B.SilkS" user "Ref Des/Silkscreen Bottom")
		(1 "F.Mask" user "Board Geometry/Soldermask Top")
		(3 "B.Mask" user "Board Geometry/Soldermask Bottom")
		(17 "Dwgs.User" user "User.Drawings")
		(19 "Cmts.User" user "User.Comments")
		(21 "Eco1.User" user "User.Eco1")
		(23 "Eco2.User" user "User.Eco2")
		(25 "Edge.Cuts" user "Board Geometry/Outline")
		(27 "Margin" user)
		(31 "F.CrtYd" user "Package Geometry/Place Bound Top")
		(29 "B.CrtYd" user "Package Geometry/Place Bound Bottom")
		(35 "F.Fab" user "Ref Des/Assembly Top")
		(33 "B.Fab" user "Ref Des/Assembly Bottom")
	)
	(footprint ""
		(layer "B.Cu")
		(at 367.975388 -175.106076 90)
		(property "Reference" "PR324"
			(at 0 0 90)
			(layer "B.SilkS")
			(hide yes)
			(effects
				(font
					(size 1.27 1.27)
				)
				(justify mirror)
			)
		)
		(property "Value" ""
			(at 0 0 90)
			(layer "B.Fab")
			(effects
				(font
					(size 1.27 1.27)
				)
				(justify mirror)
			)
		)
		(duplicate_pad_numbers_are_jumpers no)
		(fp_line
			(start 0.7874 -0.4064)
			(end -0.7874 -0.4064)
			(stroke
				(width 0.1524)
				(type default)
			)
			(layer "B.SilkS")
		)
		(fp_line
			(start -0.7874 -0.4064)
			(end -0.7874 0.4064)
			(stroke
				(width 0.1524)
				(type default)
			)
			(layer "B.SilkS")
		)
		(fp_line
			(start 0.7874 0.4064)
			(end 0.7874 -0.4064)
			(stroke
				(width 0.1524)
				(type default)
			)
			(layer "B.SilkS")
		)
		(fp_line
			(start -0.7874 0.4064)
			(end 0.7874 0.4064)
			(stroke
				(width 0.1524)
				(type default)
			)
			(layer "B.SilkS")
		)
		(fp_line
			(start 0.67945 -0.305054)
			(end 0.12065 -0.305054)
			(stroke
				(width 0.1)
				(type default)
			)
			(layer "B.Fab")
		)
		(fp_line
			(start 0.12065 -0.305054)
			(end 0.12065 -0.2794)
			(stroke
				(width 0.1)
				(type default)
			)
			(layer "B.Fab")
		)
		(fp_line
			(start -0.12065 -0.3048)
			(end -0.67945 -0.3048)
			(stroke
				(width 0.1)
				(type default)
			)
			(layer "B.Fab")
		)
		(fp_line
			(start -0.67945 -0.3048)
			(end -0.67945 0.3048)
			(stroke
				(width 0.1)
				(type default)
			)
			(layer "B.Fab")
		)
		(fp_line
			(start 0.12065 -0.2794)
			(end -0.12065 -0.2794)
			(stroke
				(width 0.1)
				(type default)
			)
			(layer "B.Fab")
		)
		(fp_line
			(start -0.12065 -0.2794)
			(end -0.12065 -0.3048)
			(stroke
				(width 0.1)
				(type default)
			)
			(layer "B.Fab")
		)
		(fp_line
			(start 0.12065 0.2794)
			(end 0.12065 0.3048)
			(stroke
				(width 0.1)
				(type default)
			)
			(layer "B.Fab")
		)
		(fp_line
			(start -0.120396 0.2794)
			(end 0.12065 0.2794)
			(stroke
				(width 0.1)
				(type default)
			)
			(layer "B.Fab")
		)
		(fp_line
			(start 0.67945 0.3048)
			(end 0.67945 -0.305054)
			(stroke
				(width 0.1)
				(type default)
			)
			(layer "B.Fab")
		)
		(fp_line
			(start 0.12065 0.3048)
			(end 0.67945 0.3048)
			(stroke
				(width 0.1)
				(type default)
			)
			(layer "B.Fab")
		)
		(fp_line
			(start -0.120396 0.3048)
			(end -0.120396 0.2794)
			(stroke
				(width 0.1)
				(type default)
			)
			(layer "B.Fab")
		)
		(fp_line
			(start -0.67945 0.3048)
			(end -0.120396 0.3048)
			(stroke
				(width 0.1)
				(type default)
			)
			(layer "B.Fab")
		)
		(pad "1" smd circle
			(at 0.40005 0 270)
			(size 0 0)
			(layers "B.Cu" "B.Mask" "B.Paste")
			(net "PVDDCR_CPU0_P0_VOS1")
		)
		(pad "2" smd circle
			(at -0.40005 0 270)
			(size 0 0)
			(layers "B.Cu" "B.Mask" "B.Paste")
			(net "PVDDCR_CPU0_P0")
		)
	)
	(footprint ""
		(layer "B.Cu")
		(at 355.111304 -395.148562 90)
		(property "Reference" "C653"
			(at 0 0 90)
			(layer "B.SilkS")
			(hide yes)
			(effects
				(font
					(size 1.27 1.27)
				)
				(justify mirror)
			)
		)
		(property "Value" ""
			(at 0 0 90)
			(layer "B.Fab")
			(effects
				(font
					(size 1.27 1.27)
				)
				(justify mirror)
			)
		)
		(duplicate_pad_numbers_are_jumpers no)
		(fp_line
			(start 0.299974 -0.150114)
			(end -0.299974 -0.150114)
			(stroke
				(width 0.1)
				(type default)
			)
			(layer "B.Fab")
		)
		(fp_line
			(start -0.299974 -0.150114)
			(end -0.299974 0.150114)
			(stroke
				(width 0.1)
				(type default)
			)
			(layer "B.Fab")
		)
		(fp_line
			(start 0.299974 0.150114)
			(end 0.299974 -0.150114)
			(stroke
				(width 0.1)
				(type default)
			)
			(layer "B.Fab")
		)
		(fp_line
			(start -0.299974 0.150114)
			(end 0.299974 0.150114)
			(stroke
				(width 0.1)
				(type default)
			)
			(layer "B.Fab")
		)
		(pad "1" smd rect
			(at 0.2667 0 270)
			(size 0.3048 0.381)
			(layers "B.Cu" "B.Mask" "B.Paste")
			(net "P0V9_CPU0_RT1_2A")
		)
		(pad "2" smd rect
			(at -0.2667 0 270)
			(size 0.3048 0.381)
			(layers "B.Cu" "B.Mask" "B.Paste")
			(net "GND")
		)
	)
	(footprint ""
		(layer "B.Cu")
		(at 90.590878 -189.461648 90)
		(property "Reference" "PC276"
			(at 6.607556 -0.649986 270)
			(unlocked yes)
			(layer "B.SilkS")
			(effects
				(font
					(size 0.7874 0.5842)
					(thickness 0.1524)
				)
				(justify left mirror)
			)
		)
		(property "Value" ""
			(at 0 0 90)
			(layer "B.Fab")
			(effects
				(font
					(size 1.27 1.27)
				)
				(justify mirror)
			)
		)
		(duplicate_pad_numbers_are_jumpers no)
		(fp_line
			(start 4.533392 -2.249932)
			(end -4.533392 -2.249932)
			(stroke
				(width 0.1524)
				(type default)
			)
			(layer "B.SilkS")
		)
		(fp_line
			(start -4.533392 -2.249932)
			(end -4.533392 2.249932)
			(stroke
				(width 0.1524)
				(type default)
			)
			(layer "B.SilkS")
		)
		(fp_line
			(start 4.533392 2.249932)
			(end 4.533392 -2.249932)
			(stroke
				(width 0.1524)
				(type default)
			)
			(layer "B.SilkS")
		)
		(fp_line
			(start -4.533392 2.249932)
			(end 4.533392 2.249932)
			(stroke
				(width 0.1524)
				(type default)
			)
			(layer "B.SilkS")
		)
		(fp_rect
			(start 4.533392 -2.326132)
			(end 5.39242 2.326132)
			(stroke
				(width 0)
				(type default)
			)
			(fill yes)
			(layer "B.SilkS")
		)
		(fp_line
			(start 3.750056 -2.249932)
			(end -3.750056 -2.249932)
			(stroke
				(width 0.1)
				(type default)
			)
			(layer "B.Fab")
		)
		(fp_line
			(start -3.750056 -2.249932)
			(end -3.750056 2.249932)
			(stroke
				(width 0.1)
				(type default)
			)
			(layer "B.Fab")
		)
		(fp_line
			(start 3.750056 2.249932)
			(end 3.750056 -2.249932)
			(stroke
				(width 0.1)
				(type default)
			)
			(layer "B.Fab")
		)
		(fp_line
			(start -3.750056 2.249932)
			(end 3.750056 2.249932)
			(stroke
				(width 0.1)
				(type default)
			)
			(layer "B.Fab")
		)
		(fp_text user "-"
			(at -4.8514 -0.14605 90)
			(unlocked yes)
			(layer "B.SilkS")
			(effects
				(font
					(size 1.905 1.4224)
					(thickness 0.1524)
				)
				(justify left mirror)
			)
		)
		(fp_text user "+"
			(at 6.322314 0.786384 0)
			(unlocked yes)
			(layer "B.SilkS")
			(effects
				(font
					(size 1.905 1.4224)
					(thickness 0.1524)
				)
				(justify left mirror)
			)
		)
		(fp_text user "-"
			(at -4.8514 -0.14605 90)
			(unlocked yes)
			(layer "B.Fab")
			(effects
				(font
					(size 1.905 1.4224)
					(thickness 0.1524)
				)
				(justify left mirror)
			)
		)
		(fp_text user "+"
			(at 6.322314 0.786384 0)
			(unlocked yes)
			(layer "B.Fab")
			(effects
				(font
					(size 1.905 1.4224)
					(thickness 0.1524)
				)
				(justify left mirror)
			)
		)
		(pad "1" smd rect
			(at 3.199892 0 270)
			(size 2.413 2.8194)
			(layers "B.Cu" "B.Mask" "B.Paste")
			(net "PVDDCR_CPU0_P1")
		)
		(pad "2" smd rect
			(at -3.199892 0 270)
			(size 2.413 2.8194)
			(layers "B.Cu" "B.Mask" "B.Paste")
			(net "GND")
		)
	)
)
